# BASEBOARD_FAB2 (Tioga Pass) — schematic netlist excerpt (pin names and nets, part order shuffled) for the footprints in the layout excerpt that follows; sources: Cadence DE-HDL packaged netlist, KiCad conversion of Wiwynn_Tioga_Pass_MB.brd

J1F1  DM-FCI-CONN76-8R-GP-U-01  pkg CONN-G4  page 181
  PCIE_RX_DP0  = P3E_CPU1_PE3_MP_RXN<0>
  GND1  = GND
  PCIE_RX_DP6  = P3E_CPU1_PE3_MP_RXP<6>
  FAN_TACH3  = FAN_TACH3_R
  MNG_TX_DP  = NIC_MDI_MNG_TX_DP
  \pmbus_alert#\  = IRQ_SML1_PMBUS_ALERT_R_N
  PCIE_TX_DP3  = P3E_CPU1_PE3_MP_C_TXN<3>
  GND2  = GND
  PCIE_RX_DN0  = P3E_CPU1_PE3_MP_RXP<0>
  PCIE_RX_DP3  = P3E_CPU1_PE3_MP_RXN<3>
  PCIE_RX_DN6  = P3E_CPU1_PE3_MP_RXN<6>
  FAN_TACH2  = FAN_TACH2_R
  MNG_TX_DN  = NIC_MDI_MNG_TX_DN
  PMBUS_DATA  = SMB_BMC_PMBUS_STBY_LVC3_SDA
  PCIE_TX_DN3  = P3E_CPU1_PE3_MP_C_TXP<3>
  PCIE_TX_DP0  = P3E_CPU1_PE3_MP_C_TXN<0>
  GND3  = GND
  PCIE_RX_DN3  = P3E_CPU1_PE3_MP_RXP<3>
  GND4  = GND
  FAN_TACH1  = FAN_TACH1_R
  GND5  = GND
  PMBUS_CLK  = SMB_BMC_PMBUS_STBY_LVC3_SCL
  GND6  = GND
  PCIE_TX_DN0  = P3E_CPU1_PE3_MP_C_TXP<0>
  PCIE_RX_DP1  = P3E_CPU1_PE3_MP_RXN<1>
  GND7  = GND
  PCIE_RX_DP7  = P3E_CPU1_PE3_MP_RXN<7>
  FAN_TACH0  = FAN_TACH0_R
  MNG_RX_DP  = NIC_MDI_MNG_RX_DP
  GND8  = GND
  PCIE_TX_DP4  = P3E_CPU1_PE3_MP_C_TXN<4>
  GND9  = GND
  PCIE_RX_DN1  = P3E_CPU1_PE3_MP_RXP<1>
  PCIE_RX_DP4  = P3E_CPU1_PE3_MP_RXN<4>
  PCIE_RX_DN7  = P3E_CPU1_PE3_MP_RXP<7>
  \mated_in#\  = FM_MATED_IN_N
  MNG_RX_DN  = NIC_MDI_MNG_RX_DN
  PCIE_TX_DP6  = P3E_CPU1_PE3_MP_C_TXN<6>
  PCIE_TX_DN4  = P3E_CPU1_PE3_MP_C_TXP<4>
  PCIE_TX_DP1  = P3E_CPU1_PE3_MP_C_TXN<1>
  GND10  = GND
  PCIE_RX_DN4  = P3E_CPU1_PE3_MP_RXP<4>
  GND11  = GND
  FAN_PWM0  = FAN_PWM_OUT_SYS0_R1
  MB_SLOT_ID0  = FM_MB_SLOT_ID0
  PCIE_TX_DN6  = P3E_CPU1_PE3_MP_C_TXP<6>
  GND12  = GND
  PCIE_TX_DN1  = P3E_CPU1_PE3_MP_C_TXP<1>
  PCIE_RX_DP2  = P3E_CPU1_PE3_MP_RXP<2>
  GND13  = GND
  COM_TX  = SPA_MID_DBG_TX_R
  GND14  = GND
  MB_SLOT_ID1  = FM_MB_SLOT_ID1
  GND15  = GND
  PCIE_TX_DP5  = P3E_CPU1_PE3_MP_C_TXP<5>
  GND16  = GND
  PCIE_RX_DN2  = P3E_CPU1_PE3_MP_RXN<2>
  PCIE_RX_DP5  = P3E_CPU1_PE3_MP_RXP<5>
  COM_RX  = SPA_MID_DBG_RX_R
  PCIE_CLK_100M_DP  = CLK_100M_AIRMAX8_PE1_DP
  MB_SLOT_ID2  = FM_MB_SLOT_ID2
  PCIE_TX_DP7  = P3E_CPU1_PE3_MP_C_TXP<7>
  PCIE_TX_DN5  = P3E_CPU1_PE3_MP_C_TXN<5>
  PCIE_TX_DP2  = P3E_CPU1_PE3_MP_C_TXN<2>
  GND17  = GND
  PCIE_RX_DN5  = P3E_CPU1_PE3_MP_RXN<5>
  \mb_on#\  = FM_ENABLE_FAN_POWER
  PCIE_CLK_100M_DN  = CLK_100M_AIRMAX8_PE1_DN
  \pcie_perst#\  = RST_PCIE_MIDPLANE_N
  PCIE_TX_DN7  = P3E_CPU1_PE3_MP_C_TXN<7>
  GND18  = GND
  PCIE_TX_DN2  = P3E_CPU1_PE3_MP_C_TXP<2>
  J2  = GND
  J4  = GND
  J6  = GND
  J8  = GND

(kicad_pcb
	(version 20260206)
	(generator "pcbnew")
	(generator_version "10.0")
	(general
		(thickness 1.6)
		(legacy_teardrops no)
	)
	(paper "A4")
	(title_block
		(title "Wiwynn_Tioga_Pass_MB.brd")
		(comment 1 "Tioga Pass / footprint 1465 of 4770 (J1F1), pads 30-58 of 76")
	)
	(layers
		(0 "F.Cu" signal "TOP")
		(4 "In1.Cu" signal "L2GND")
		(6 "In2.Cu" signal "L3")
		(8 "In3.Cu" signal "L4GND")
		(10 "In4.Cu" signal "L5")
		(12 "In5.Cu" signal "L6GND")
		(14 "In6.Cu" signal "L7VCC")
		(16 "In7.Cu" signal "L8VCC")
		(18 "In8.Cu" signal "L9GND")
		(20 "In9.Cu" signal "L10")
		(22 "In10.Cu" signal "L11GND")
		(24 "In11.Cu" signal "L12")
		(26 "In12.Cu" signal "L13GND")
		(2 "B.Cu" signal "BOTTOM")
		(9 "F.Adhes" user "F.Adhesive")
		(11 "B.Adhes" user "B.Adhesive")
		(13 "F.Paste" user "Package Geometry/Pastemask Top")
		(15 "B.Paste" user "Package Geometry/Pastemask Bottom")
		(5 "F.SilkS" user "Ref Des/Silkscreen Top")
		(7 "B.SilkS" user "Ref Des/Silkscreen Bottom")
		(1 "F.Mask" user "Board Geometry/Soldermask Top")
		(3 "B.Mask" user "Board Geometry/Soldermask Bottom")
		(17 "Dwgs.User" user "User.Drawings")
		(19 "Cmts.User" user "User.Comments")
		(21 "Eco1.User" user "User.Eco1")
		(23 "Eco2.User" user "User.Eco2")
		(25 "Edge.Cuts" user "Board Geometry/Outline")
		(27 "Margin" user)
		(31 "F.CrtYd" user "Package Geometry/Place Bound Top")
		(29 "B.CrtYd" user "Package Geometry/Place Bound Bottom")
		(35 "F.Fab" user "Ref Des/Assembly Top")
		(33 "B.Fab" user "Ref Des/Assembly Bottom")
	)
	(footprint ""
		(layer "F.Cu")
		(at 2.29997 -32.71012 -90)
		(property "Reference" "J1F1"
			(at 0 0 270)
			(layer "F.SilkS")
			(hide yes)
			(effects
				(font
					(size 1.27 1.27)
				)
			)
		)
		(property "Value" "*"
			(at -20.8026 -3.4036 270)
			(unlocked yes)
			(layer "F.Fab")
			(hide yes)
			(effects
				(font
					(size 1.27 1.016)
					(thickness 0.1524)
				)
			)
		)
		(property "Device Type" "DM-FCI-CONN76-8R-GP-U-01_CONN-A"
			(at -20.8026 -4.9276 270)
			(unlocked yes)
			(layer "F.Fab")
			(hide yes)
			(effects
				(font
					(size 1.27 1.016)
					(thickness 0.1524)
				)
			)
		)
		(duplicate_pad_numbers_are_jumpers no)
		(pad "D6" thru_hole circle
			(at 2.999994 2.100072 270)
			(size 0.8636 0.8636)
			(drill 0.499872)
			(layers "*.Cu" "*.Mask")
			(remove_unused_layers no)
			(net "GND")
			(clearance 0.1778)
			(thermal_gap 0.1778)
		)
		(pad "D7" thru_hole circle
			(at 4.99999 1.999996 270)
			(size 0.8128 0.8128)
			(drill 0.399796)
			(layers "*.Cu" "*.Mask")
			(remove_unused_layers no)
			(net "P3E_CPU1_PE3_MP_C_TXN<4>")
			(clearance 0.2921)
			(thermal_gap 0.2921)
		)
		(pad "D8" thru_hole circle
			(at 6.999986 2.100072 270)
			(size 0.8636 0.8636)
			(drill 0.499872)
			(layers "*.Cu" "*.Mask")
			(remove_unused_layers no)
			(net "GND")
			(clearance 0.1778)
			(thermal_gap 0.1778)
		)
		(pad "E1" thru_hole circle
			(at -6.999986 0.599948 270)
			(size 0.8128 0.8128)
			(drill 0.399796)
			(layers "*.Cu" "*.Mask")
			(remove_unused_layers no)
			(net "P3E_CPU1_PE3_MP_RXP<1>")
			(clearance 0.2921)
			(thermal_gap 0.2921)
		)
		(pad "E2" thru_hole circle
			(at -4.99999 0.700024 270)
			(size 0.8128 0.8128)
			(drill 0.399796)
			(layers "*.Cu" "*.Mask")
			(remove_unused_layers no)
			(net "P3E_CPU1_PE3_MP_RXN<4>")
			(clearance 0.2921)
			(thermal_gap 0.2921)
		)
		(pad "E3" thru_hole circle
			(at -2.999994 0.599948 270)
			(size 0.8128 0.8128)
			(drill 0.399796)
			(layers "*.Cu" "*.Mask")
			(remove_unused_layers no)
			(net "P3E_CPU1_PE3_MP_RXP<7>")
			(clearance 0.2921)
			(thermal_gap 0.2921)
		)
		(pad "E4" thru_hole circle
			(at -0.999998 0.700024 270)
			(size 0.8128 0.8128)
			(drill 0.399796)
			(layers "*.Cu" "*.Mask")
			(remove_unused_layers no)
			(net "FM_MATED_IN_N")
			(clearance 0.1524)
			(thermal_gap 0.1524)
		)
		(pad "E5" thru_hole circle
			(at 0.999998 0.599948 270)
			(size 0.8128 0.8128)
			(drill 0.399796)
			(layers "*.Cu" "*.Mask")
			(remove_unused_layers no)
			(net "NIC_MDI_MNG_RX_DN")
			(clearance 0.2921)
			(thermal_gap 0.2921)
		)
		(pad "E6" thru_hole circle
			(at 2.999994 0.700024 270)
			(size 0.8128 0.8128)
			(drill 0.399796)
			(layers "*.Cu" "*.Mask")
			(remove_unused_layers no)
			(net "P3E_CPU1_PE3_MP_C_TXN<6>")
			(clearance 0.2921)
			(thermal_gap 0.2921)
		)
		(pad "E7" thru_hole circle
			(at 4.99999 0.599948 270)
			(size 0.8128 0.8128)
			(drill 0.399796)
			(layers "*.Cu" "*.Mask")
			(remove_unused_layers no)
			(net "P3E_CPU1_PE3_MP_C_TXP<4>")
			(clearance 0.2921)
			(thermal_gap 0.2921)
		)
		(pad "E8" thru_hole circle
			(at 6.999986 0.700024 270)
			(size 0.8128 0.8128)
			(drill 0.399796)
			(layers "*.Cu" "*.Mask")
			(remove_unused_layers no)
			(net "P3E_CPU1_PE3_MP_C_TXN<1>")
			(clearance 0.2921)
			(thermal_gap 0.2921)
		)
		(pad "F1" thru_hole circle
			(at -6.999986 -0.8001 270)
			(size 0.8636 0.8636)
			(drill 0.499872)
			(layers "*.Cu" "*.Mask")
			(remove_unused_layers no)
			(net "GND")
			(clearance 0.1778)
			(thermal_gap 0.1778)
		)
		(pad "F2" thru_hole circle
			(at -4.99999 -0.700024 270)
			(size 0.8128 0.8128)
			(drill 0.399796)
			(layers "*.Cu" "*.Mask")
			(remove_unused_layers no)
			(net "P3E_CPU1_PE3_MP_RXP<4>")
			(clearance 0.2921)
			(thermal_gap 0.2921)
		)
		(pad "F3" thru_hole circle
			(at -2.999994 -0.8001 270)
			(size 0.8636 0.8636)
			(drill 0.499872)
			(layers "*.Cu" "*.Mask")
			(remove_unused_layers no)
			(net "GND")
			(clearance 0.1778)
			(thermal_gap 0.1778)
		)
		(pad "F4" thru_hole circle
			(at -0.999998 -0.700024 270)
			(size 0.8128 0.8128)
			(drill 0.399796)
			(layers "*.Cu" "*.Mask")
			(remove_unused_layers no)
			(net "FAN_PWM_OUT_SYS0_R1")
			(clearance 0.1524)
			(thermal_gap 0.1524)
		)
		(pad "F5" thru_hole circle
			(at 0.999998 -0.8001 270)
			(size 0.8636 0.8636)
			(drill 0.499872)
			(layers "*.Cu" "*.Mask")
			(remove_unused_layers no)
			(net "FM_MB_SLOT_ID0")
			(clearance 0.1778)
			(thermal_gap 0.1778)
		)
		(pad "F6" thru_hole circle
			(at 2.999994 -0.700024 270)
			(size 0.8128 0.8128)
			(drill 0.399796)
			(layers "*.Cu" "*.Mask")
			(remove_unused_layers no)
			(net "P3E_CPU1_PE3_MP_C_TXP<6>")
			(clearance 0.2921)
			(thermal_gap 0.2921)
		)
		(pad "F7" thru_hole circle
			(at 4.99999 -0.8001 270)
			(size 0.8636 0.8636)
			(drill 0.499872)
			(layers "*.Cu" "*.Mask")
			(remove_unused_layers no)
			(net "GND")
			(clearance 0.1778)
			(thermal_gap 0.1778)
		)
		(pad "F8" thru_hole circle
			(at 6.999986 -0.700024 270)
			(size 0.8128 0.8128)
			(drill 0.399796)
			(layers "*.Cu" "*.Mask")
			(remove_unused_layers no)
			(net "P3E_CPU1_PE3_MP_C_TXP<1>")
			(clearance 0.2921)
			(thermal_gap 0.2921)
		)
		(pad "G1" thru_hole circle
			(at -6.999986 -2.199894 270)
			(size 0.8128 0.8128)
			(drill 0.399796)
			(layers "*.Cu" "*.Mask")
			(remove_unused_layers no)
			(net "P3E_CPU1_PE3_MP_RXP<2>")
			(clearance 0.2921)
			(thermal_gap 0.2921)
		)
		(pad "G2" thru_hole circle
			(at -4.99999 -2.100072 270)
			(size 0.8636 0.8636)
			(drill 0.499872)
			(layers "*.Cu" "*.Mask")
			(remove_unused_layers no)
			(net "GND")
			(clearance 0.1778)
			(thermal_gap 0.1778)
		)
		(pad "G3" thru_hole circle
			(at -2.999994 -2.199894 270)
			(size 0.8128 0.8128)
			(drill 0.399796)
			(layers "*.Cu" "*.Mask")
			(remove_unused_layers no)
			(net "SPA_MID_DBG_TX_R")
			(clearance 0.1524)
			(thermal_gap 0.1524)
		)
		(pad "G4" thru_hole circle
			(at -0.999998 -2.100072 270)
			(size 0.8636 0.8636)
			(drill 0.499872)
			(layers "*.Cu" "*.Mask")
			(remove_unused_layers no)
			(net "GND")
			(clearance 0.1778)
			(thermal_gap 0.1778)
		)
		(pad "G5" thru_hole circle
			(at 0.999998 -2.199894 270)
			(size 0.8128 0.8128)
			(drill 0.399796)
			(layers "*.Cu" "*.Mask")
			(remove_unused_layers no)
			(net "FM_MB_SLOT_ID1")
			(clearance 0.1524)
			(thermal_gap 0.1524)
		)
		(pad "G6" thru_hole circle
			(at 2.999994 -2.100072 270)
			(size 0.8636 0.8636)
			(drill 0.499872)
			(layers "*.Cu" "*.Mask")
			(remove_unused_layers no)
			(net "GND")
			(clearance 0.1778)
			(thermal_gap 0.1778)
		)
		(pad "G7" thru_hole circle
			(at 4.99999 -2.199894 270)
			(size 0.8128 0.8128)
			(drill 0.399796)
			(layers "*.Cu" "*.Mask")
			(remove_unused_layers no)
			(net "P3E_CPU1_PE3_MP_C_TXP<5>")
			(clearance 0.2921)
			(thermal_gap 0.2921)
		)
		(pad "G8" thru_hole circle
			(at 6.999986 -2.100072 270)
			(size 0.8636 0.8636)
			(drill 0.499872)
			(layers "*.Cu" "*.Mask")
			(remove_unused_layers no)
			(net "GND")
			(clearance 0.1778)
			(thermal_gap 0.1778)
		)
		(pad "H1" thru_hole circle
			(at -6.999986 -3.599942 270)
			(size 0.8128 0.8128)
			(drill 0.399796)
			(layers "*.Cu" "*.Mask")
			(remove_unused_layers no)
			(net "P3E_CPU1_PE3_MP_RXN<2>")
			(clearance 0.2921)
			(thermal_gap 0.2921)
		)
		(pad "H2" thru_hole circle
			(at -4.99999 -3.50012 270)
			(size 0.8128 0.8128)
			(drill 0.399796)
			(layers "*.Cu" "*.Mask")
			(remove_unused_layers no)
			(net "P3E_CPU1_PE3_MP_RXP<5>")
			(clearance 0.2921)
			(thermal_gap 0.2921)
		)
	)
)
